# BASEBOARD_FAB2 (Tioga Pass) — schematic netlist excerpt (pin names and nets, part order shuffled) for the footprints in the layout excerpt that follows; sources: Cadence DE-HDL packaged netlist, KiCad conversion of Wiwynn_Tioga_Pass_MB.brd

C5D35  CAP_A  22.0UF 4V 20% X6S  pkg 0603V  page 42 : A = PVCCMCP_CPU0 ; B = GND
C8G3  CAP  0.22UF 16V 10% X7R  pkg 0402  page 105 : A = P3E_CPU0_PE2_SS_TXP<3> ; B = P3E_CPU0_PE2_SS_C_TXP<3>
R9E8  RES  33.2 1% CHIP  pkg 0402  page 139 : A = SPI_NIC_SCLK_R ; B = SPI_NIC_SCLK

(kicad_pcb
	(version 20260206)
	(generator "pcbnew")
	(generator_version "10.0")
	(general
		(thickness 1.6)
		(legacy_teardrops no)
	)
	(paper "A4")
	(title_block
		(title "Wiwynn_Tioga_Pass_MB.brd")
		(comment 1 "Tioga Pass / footprints 708-710 of 4770")
	)
	(layers
		(0 "F.Cu" signal "TOP")
		(4 "In1.Cu" signal "L2GND")
		(6 "In2.Cu" signal "L3")
		(8 "In3.Cu" signal "L4GND")
		(10 "In4.Cu" signal "L5")
		(12 "In5.Cu" signal "L6GND")
		(14 "In6.Cu" signal "L7VCC")
		(16 "In7.Cu" signal "L8VCC")
		(18 "In8.Cu" signal "L9GND")
		(20 "In9.Cu" signal "L10")
		(22 "In10.Cu" signal "L11GND")
		(24 "In11.Cu" signal "L12")
		(26 "In12.Cu" signal "L13GND")
		(2 "B.Cu" signal "BOTTOM")
		(9 "F.Adhes" user "F.Adhesive")
		(11 "B.Adhes" user "B.Adhesive")
		(13 "F.Paste" user "Package Geometry/Pastemask Top")
		(15 "B.Paste" user "Package Geometry/Pastemask Bottom")
		(5 "F.SilkS" user "Ref Des/Silkscreen Top")
		(7 "B.SilkS" user "Ref Des/Silkscreen Bottom")
		(1 "F.Mask" user "Board Geometry/Soldermask Top")
		(3 "B.Mask" user "Board Geometry/Soldermask Bottom")
		(17 "Dwgs.User" user "User.Drawings")
		(19 "Cmts.User" user "User.Comments")
		(21 "Eco1.User" user "User.Eco1")
		(23 "Eco2.User" user "User.Eco2")
		(25 "Edge.Cuts" user "Board Geometry/Outline")
		(27 "Margin" user)
		(31 "F.CrtYd" user "Package Geometry/Place Bound Top")
		(29 "B.CrtYd" user "Package Geometry/Place Bound Bottom")
		(35 "F.Fab" user "Ref Des/Assembly Top")
		(33 "B.Fab" user "Ref Des/Assembly Bottom")
	)
	(footprint ""
		(layer "F.Cu")
		(at 490.2581 -46.7614 90)
		(property "Reference" "R9E8"
			(at 0 0 90)
			(layer "F.SilkS")
			(hide yes)
			(effects
				(font
					(size 1.27 1.27)
				)
			)
		)
		(property "Value" ""
			(at 0 0 90)
			(layer "F.Fab")
			(effects
				(font
					(size 1.27 1.27)
				)
			)
		)
		(duplicate_pad_numbers_are_jumpers no)
		(fp_poly
			(pts
				(xy -0.2794 -0.1016) (xy 0.2794 -0.1016) (xy 0.2794 0.9906) (xy -0.2794 0.9906)
			)
			(stroke
				(width 0)
				(type default)
			)
			(fill no)
			(layer "F.CrtYd")
		)
		(fp_line
			(start 0.2794 -0.1016)
			(end -0.2794 -0.1016)
			(stroke
				(width 0.1)
				(type default)
			)
			(layer "F.Fab")
		)
		(fp_line
			(start -0.2794 -0.1016)
			(end -0.2794 0.9906)
			(stroke
				(width 0.1)
				(type default)
			)
			(layer "F.Fab")
		)
		(fp_line
			(start 0.2794 0.9906)
			(end 0.2794 -0.1016)
			(stroke
				(width 0.1)
				(type default)
			)
			(layer "F.Fab")
		)
		(fp_line
			(start -0.2794 0.9906)
			(end 0.2794 0.9906)
			(stroke
				(width 0.1)
				(type default)
			)
			(layer "F.Fab")
		)
		(pad "1" smd rect
			(at 0 0 90)
			(size 0.508 0.508)
			(layers "F.Cu" "F.Mask" "F.Paste")
			(net "SPI_NIC_SCLK_R")
		)
		(pad "2" smd rect
			(at 0 0.889 90)
			(size 0.508 0.508)
			(layers "F.Cu" "F.Mask" "F.Paste")
			(net "SPI_NIC_SCLK")
		)
		(zone
			(layer "F.Cu")
			(hatch none 0.5)
			(connect_pads
				(clearance 0)
			)
			(min_thickness 0.25)
			(keepout
				(tracks allowed)
				(vias not_allowed)
				(pads allowed)
				(copperpour not_allowed)
				(footprints allowed)
			)
			(placement
				(enabled no)
				(sheetname "")
			)
			(fill
				(thermal_gap 0.5)
				(thermal_bridge_width 0.5)
				(island_removal_mode 0)
			)
			(polygon
				(pts
					(xy 490.5121 -46.5074) (xy 490.5121 -47.0154) (xy 490.8931 -47.0154) (xy 490.8931 -46.5074)
				)
			)
		)
		(zone
			(layer "F.Cu")
			(hatch none 0.5)
			(connect_pads
				(clearance 0)
			)
			(min_thickness 0.25)
			(keepout
				(tracks not_allowed)
				(vias allowed)
				(pads allowed)
				(copperpour not_allowed)
				(footprints allowed)
			)
			(placement
				(enabled no)
				(sheetname "")
			)
			(fill
				(thermal_gap 0.5)
				(thermal_bridge_width 0.5)
				(island_removal_mode 0)
			)
			(polygon
				(pts
					(xy 490.8931 -46.5074) (xy 490.8931 -47.0154) (xy 490.5121 -47.0154) (xy 490.5121 -46.5074)
				)
			)
		)
	)
	(footprint ""
		(layer "F.Cu")
		(at 402.830792 -10.917936)
		(property "Reference" "C8G3"
			(at 0 0 0)
			(layer "F.SilkS")
			(hide yes)
			(effects
				(font
					(size 1.27 1.27)
				)
			)
		)
		(property "Value" ""
			(at 0 0 0)
			(layer "F.Fab")
			(effects
				(font
					(size 1.27 1.27)
				)
			)
		)
		(duplicate_pad_numbers_are_jumpers no)
		(fp_rect
			(start -0.3048 0.9906)
			(end 0.3048 -0.1016)
			(stroke
				(width 0)
				(type default)
			)
			(fill no)
			(layer "F.CrtYd")
		)
		(fp_line
			(start -0.3048 -0.1016)
			(end -0.3048 0.9906)
			(stroke
				(width 0.1)
				(type default)
			)
			(layer "F.Fab")
		)
		(fp_line
			(start -0.3048 0.9906)
			(end 0.3048 0.9906)
			(stroke
				(width 0.1)
				(type default)
			)
			(layer "F.Fab")
		)
		(fp_line
			(start 0.3048 -0.1016)
			(end -0.3048 -0.1016)
			(stroke
				(width 0.1)
				(type default)
			)
			(layer "F.Fab")
		)
		(fp_line
			(start 0.3048 0.9906)
			(end 0.3048 -0.1016)
			(stroke
				(width 0.1)
				(type default)
			)
			(layer "F.Fab")
		)
		(pad "1" smd rect
			(at 0 0)
			(size 0.508 0.508)
			(layers "F.Cu" "F.Mask" "F.Paste")
			(net "P3E_CPU0_PE2_SS_TXP<3>")
		)
		(pad "2" smd rect
			(at 0 0.889)
			(size 0.508 0.508)
			(layers "F.Cu" "F.Mask" "F.Paste")
			(net "P3E_CPU0_PE2_SS_C_TXP<3>")
		)
		(zone
			(layer "F.Cu")
			(hatch none 0.5)
			(connect_pads
				(clearance 0)
			)
			(min_thickness 0.25)
			(keepout
				(tracks not_allowed)
				(vias allowed)
				(pads allowed)
				(copperpour not_allowed)
				(footprints allowed)
			)
			(placement
				(enabled no)
				(sheetname "")
			)
			(fill
				(thermal_gap 0.5)
				(thermal_bridge_width 0.5)
				(island_removal_mode 0)
			)
			(polygon
				(pts
					(xy 402.576792 -10.282936) (xy 403.084792 -10.282936) (xy 403.084792 -10.663936) (xy 402.576792 -10.663936)
				)
			)
		)
		(zone
			(layer "F.Cu")
			(hatch none 0.5)
			(connect_pads
				(clearance 0)
			)
			(min_thickness 0.25)
			(keepout
				(tracks allowed)
				(vias not_allowed)
				(pads allowed)
				(copperpour not_allowed)
				(footprints allowed)
			)
			(placement
				(enabled no)
				(sheetname "")
			)
			(fill
				(thermal_gap 0.5)
				(thermal_bridge_width 0.5)
				(island_removal_mode 0)
			)
			(polygon
				(pts
					(xy 402.576792 -10.282936) (xy 403.084792 -10.282936) (xy 403.084792 -10.663936) (xy 402.576792 -10.663936)
				)
			)
		)
	)
	(footprint ""
		(layer "F.Cu")
		(at 271.898872 -77.636116)
		(property "Reference" "C5D35"
			(at 0 0 0)
			(layer "F.SilkS")
			(hide yes)
			(effects
				(font
					(size 1.27 1.27)
				)
			)
		)
		(property "Value" ""
			(at 0 0 0)
			(layer "F.Fab")
			(effects
				(font
					(size 1.27 1.27)
				)
			)
		)
		(duplicate_pad_numbers_are_jumpers no)
		(fp_poly
			(pts
				(xy -0.4953 -0.2032) (xy 0.4953 -0.2032) (xy 0.4953 1.6002) (xy -0.4953 1.6002)
			)
			(stroke
				(width 0)
				(type default)
			)
			(fill no)
			(layer "F.CrtYd")
		)
		(fp_line
			(start -0.4953 -0.2032)
			(end 0.4953 -0.2032)
			(stroke
				(width 0.1)
				(type default)
			)
			(layer "F.Fab")
		)
		(fp_line
			(start -0.4953 1.6002)
			(end -0.4953 -0.2032)
			(stroke
				(width 0.1)
				(type default)
			)
			(layer "F.Fab")
		)
		(fp_line
			(start 0.4953 -0.2032)
			(end 0.4953 1.6002)
			(stroke
				(width 0.1)
				(type default)
			)
			(layer "F.Fab")
		)
		(fp_line
			(start 0.4953 1.6002)
			(end -0.4953 1.6002)
			(stroke
				(width 0.1)
				(type default)
			)
			(layer "F.Fab")
		)
		(pad "1" smd rect
			(at 0 0)
			(size 0.762 0.889)
			(layers "F.Cu" "F.Mask" "F.Paste")
			(net "PVCCMCP_CPU0")
		)
		(pad "2" smd rect
			(at 0 1.397)
			(size 0.762 0.889)
			(layers "F.Cu" "F.Mask" "F.Paste")
			(net "GND")
		)
		(zone
			(layer "F.Cu")
			(hatch none 0.5)
			(connect_pads
				(clearance 0)
			)
			(min_thickness 0.25)
			(keepout
				(tracks not_allowed)
				(vias allowed)
				(pads allowed)
				(copperpour not_allowed)
				(footprints allowed)
			)
			(placement
				(enabled no)
				(sheetname "")
			)
			(fill
				(thermal_gap 0.5)
				(thermal_bridge_width 0.5)
				(island_removal_mode 0)
			)
			(polygon
				(pts
					(xy 271.517872 -77.191616) (xy 272.279872 -77.191616) (xy 272.279872 -76.683616) (xy 271.517872 -76.683616)
				)
			)
		)
	)
)
